(kicad_pcb
	(version 20260206)
	(generator "pcbnew")
	(generator_version "10.0")
	(general
		(thickness 1.6)
		(legacy_teardrops no)
	)
	(paper "A4")
	(title_block
		(title "Bryce Canyon_IOM_M2_16342-2_OCP.brd")
		(comment 1 "Bryce Canyon / footprints 147-148 of 1146")
	)
	(layers
		(0 "F.Cu" signal "TOP")
		(4 "In1.Cu" signal "L2GND")
		(6 "In2.Cu" signal "L3")
		(8 "In3.Cu" signal "L4VCC")
		(10 "In4.Cu" signal "L5VCC")
		(12 "In5.Cu" signal "L6")
		(14 "In6.Cu" signal "L7GND")
		(2 "B.Cu" signal "BOTTOM")
		(9 "F.Adhes" user "F.Adhesive")
		(11 "B.Adhes" user "B.Adhesive")
		(13 "F.Paste" user "Package Geometry/Pastemask Top")
		(15 "B.Paste" user "Package Geometry/Pastemask Bottom")
		(5 "F.SilkS" user "Ref Des/Silkscreen Top")
		(7 "B.SilkS" user "Ref Des/Silkscreen Bottom")
		(1 "F.Mask" user "Board Geometry/Soldermask Top")
		(3 "B.Mask" user "Board Geometry/Soldermask Bottom")
		(17 "Dwgs.User" user "User.Drawings")
		(19 "Cmts.User" user "User.Comments")
		(21 "Eco1.User" user "User.Eco1")
		(23 "Eco2.User" user "User.Eco2")
		(25 "Edge.Cuts" user "Board Geometry/Outline")
		(27 "Margin" user)
		(31 "F.CrtYd" user "Package Geometry/Place Bound Top")
		(29 "B.CrtYd" user "Package Geometry/Place Bound Bottom")
		(35 "F.Fab" user "Ref Des/Assembly Top")
		(33 "B.Fab" user "Ref Des/Assembly Bottom")
	)
	(footprint ""
		(layer "F.Cu")
		(at 55.530242 -166.076884)
		(property "Reference" "C520"
			(at 0 0 0)
			(layer "F.SilkS")
			(hide yes)
			(effects
				(font
					(size 1.27 1.27)
				)
			)
		)
		(property "Value" "SCD1U25V2KX-2-GP"
			(at 1.1811 -2.7051 0)
			(unlocked yes)
			(layer "F.Fab")
			(hide yes)
			(effects
				(font
					(size 1.016 1.016)
					(thickness 0.1524)
				)
			)
		)
		(property "Device Type" "C402H22"
			(at 1.1811 -4.2291 0)
			(unlocked yes)
			(layer "F.Fab")
			(hide yes)
			(effects
				(font
					(size 1.016 1.016)
					(thickness 0.1524)
				)
			)
		)
		(duplicate_pad_numbers_are_jumpers no)
		(fp_rect
			(start -0.4318 0.9525)
			(end 0.4318 -0.9525)
			(stroke
				(width 0)
				(type default)
			)
			(fill no)
			(layer "F.CrtYd")
		)
		(fp_rect
			(start -0.4318 0.9525)
			(end 0.4318 -0.9525)
			(stroke
				(width 0)
				(type default)
			)
			(fill no)
			(layer "F.Fab")
		)
		(pad "1" smd custom
			(at 0 -0.4445)
			(size 0.1524 0.1524)
			(layers "F.Cu" "F.Mask" "F.Paste")
			(net "ADC_P2V5_STBY")
			(options
				(clearance outline)
				(anchor circle)
			)
			(primitives
				(gr_poly
					(pts
						(arc
							(start 0.3048 -0.2032)
							(mid 0.275042 -0.275042)
							(end 0.2032 -0.3048)
						)
						(arc
							(start -0.2032 -0.3048)
							(mid -0.275042 -0.275042)
							(end -0.3048 -0.2032)
						)
						(arc
							(start -0.3048 0.2032)
							(mid -0.275042 0.275042)
							(end -0.2032 0.3048)
						)
						(arc
							(start 0.2032 0.3048)
							(mid 0.275042 0.275042)
							(end 0.3048 0.2032)
						)
					)
					(width 0)
					(fill yes)
				)
			)
		)
		(pad "2" smd custom
			(at 0 0.4445)
			(size 0.1524 0.1524)
			(layers "F.Cu" "F.Mask" "F.Paste")
			(net "GND")
			(options
				(clearance outline)
				(anchor circle)
			)
			(primitives
				(gr_poly
					(pts
						(arc
							(start 0.3048 -0.2032)
							(mid 0.275042 -0.275042)
							(end 0.2032 -0.3048)
						)
						(arc
							(start -0.2032 -0.3048)
							(mid -0.275042 -0.275042)
							(end -0.3048 -0.2032)
						)
						(arc
							(start -0.3048 0.2032)
							(mid -0.275042 0.275042)
							(end -0.2032 0.3048)
						)
						(arc
							(start 0.2032 0.3048)
							(mid 0.275042 0.275042)
							(end 0.3048 0.2032)
						)
					)
					(width 0)
					(fill yes)
				)
			)
		)
	)
	(footprint ""
		(layer "F.Cu")
		(at 20.034504 -142.561564)
		(property "Reference" "U28"
			(at 0 0 0)
			(layer "F.SilkS")
			(hide yes)
			(effects
				(font
					(size 1.27 1.27)
				)
			)
		)
		(property "Value" "H5AN4G6NAFR-TFC-GP"
			(at -8.423656 -15.9766 0)
			(unlocked yes)
			(layer "F.Fab")
			(hide yes)
			(effects
				(font
					(size 1.016 1.016)
					(thickness 0.1524)
				)
			)
		)
		(property "Device Type" "BGA96D075130H48"
			(at -8.423656 -17.5006 0)
			(unlocked yes)
			(layer "F.Fab")
			(hide yes)
			(effects
				(font
					(size 1.016 1.016)
					(thickness 0.1524)
				)
			)
		)
		(duplicate_pad_numbers_are_jumpers no)
		(fp_line
			(start -4.080256 -6.830314)
			(end -2.480056 -6.830314)
			(stroke
				(width 0.508)
				(type default)
			)
			(layer "F.SilkS")
		)
		(fp_line
			(start -4.080256 -5.230114)
			(end -4.080256 -6.830314)
			(stroke
				(width 0.508)
				(type default)
			)
			(layer "F.SilkS")
		)
		(fp_line
			(start -3.750056 -6.500114)
			(end -3.750056 6.500114)
			(stroke
				(width 0.1524)
				(type default)
			)
			(layer "F.SilkS")
		)
		(fp_line
			(start -3.750056 6.500114)
			(end 3.750056 6.500114)
			(stroke
				(width 0.1524)
				(type default)
			)
			(layer "F.SilkS")
		)
		(fp_line
			(start 3.750056 -6.500114)
			(end -3.750056 -6.500114)
			(stroke
				(width 0.1524)
				(type default)
			)
			(layer "F.SilkS")
		)
		(fp_line
			(start 3.750056 6.500114)
			(end 3.750056 -6.500114)
			(stroke
				(width 0.1524)
				(type default)
			)
			(layer "F.SilkS")
		)
		(fp_rect
			(start -3.750056 6.500114)
			(end 3.750056 -6.500114)
			(stroke
				(width 0)
				(type default)
			)
			(fill no)
			(layer "F.CrtYd")
		)
		(fp_poly
			(pts
				(xy -4.7498 7.5057) (xy -4.7498 -7.5057) (xy 4.7498 -7.5057) (xy 4.7498 -0.54864) (xy 3.750056 -0.54864)
				(xy 3.750056 -6.500114) (xy -3.750056 -6.500114) (xy -3.750056 6.500114) (xy 3.750056 6.500114)
				(xy 3.750056 -0.54356) (xy 4.7498 -0.54356) (xy 4.7498 7.5057)
			)
			(stroke
				(width 0)
				(type default)
			)
			(fill no)
			(layer "F.CrtYd")
		)
		(fp_rect
			(start -5.750052 8.50011)
			(end 5.750052 -8.50011)
			(stroke
				(width 0)
				(type default)
			)
			(fill no)
			(layer "F.Fab")
		)
		(pad "A1" smd circle
			(at -3.199892 -5.999988)
			(size 0.3556 0.3556)
			(layers "F.Cu" "F.Mask" "F.Paste")
			(net "P1V2_STBY")
		)
		(pad "A2" smd circle
			(at -2.400046 -5.999988)
			(size 0.3556 0.3556)
			(layers "F.Cu" "F.Mask" "F.Paste")
			(net "GND")
		)
		(pad "A3" smd circle
			(at -1.599946 -5.999988)
			(size 0.3556 0.3556)
			(layers "F.Cu" "F.Mask" "F.Paste")
			(net "MEMDQ_8")
		)
		(pad "A7" smd circle
			(at 1.599946 -5.999988)
			(size 0.3556 0.3556)
			(layers "F.Cu" "F.Mask" "F.Paste")
			(net "MEMDQS_N1")
		)
		(pad "A8" smd circle
			(at 2.400046 -5.999988)
			(size 0.3556 0.3556)
			(layers "F.Cu" "F.Mask" "F.Paste")
			(net "GND")
		)
		(pad "A9" smd circle
			(at 3.199892 -5.999988)
			(size 0.3556 0.3556)
			(layers "F.Cu" "F.Mask" "F.Paste")
			(net "P1V2_STBY")
		)
		(pad "B1" smd circle
			(at -3.199892 -5.199888)
			(size 0.3556 0.3556)
			(layers "F.Cu" "F.Mask" "F.Paste")
			(net "P2V5_STBY")
		)
		(pad "B2" smd circle
			(at -2.400046 -5.199888)
			(size 0.3556 0.3556)
			(layers "F.Cu" "F.Mask" "F.Paste")
			(net "GND")
		)
		(pad "B3" smd circle
			(at -1.599946 -5.199888)
			(size 0.3556 0.3556)
			(layers "F.Cu" "F.Mask" "F.Paste")
			(net "P1V2_STBY")
		)
		(pad "B7" smd circle
			(at 1.599946 -5.199888)
			(size 0.3556 0.3556)
			(layers "F.Cu" "F.Mask" "F.Paste")
			(net "MEMDQS_P1")
		)
		(pad "B8" smd circle
			(at 2.400046 -5.199888)
			(size 0.3556 0.3556)
			(layers "F.Cu" "F.Mask" "F.Paste")
			(net "MEMDQ_9")
		)
		(pad "B9" smd circle
			(at 3.199892 -5.199888)
			(size 0.3556 0.3556)
			(layers "F.Cu" "F.Mask" "F.Paste")
			(net "P1V2_STBY")
		)
		(pad "C1" smd circle
			(at -3.199892 -4.400042)
			(size 0.3556 0.3556)
			(layers "F.Cu" "F.Mask" "F.Paste")
			(net "P1V2_STBY")
		)
		(pad "C2" smd circle
			(at -2.400046 -4.400042)
			(size 0.3556 0.3556)
			(layers "F.Cu" "F.Mask" "F.Paste")
			(net "MEMDQ_12")
		)
		(pad "C3" smd circle
			(at -1.599946 -4.400042)
			(size 0.3556 0.3556)
			(layers "F.Cu" "F.Mask" "F.Paste")
			(net "MEMDQ_10")
		)
		(pad "C7" smd circle
			(at 1.599946 -4.400042)
			(size 0.3556 0.3556)
			(layers "F.Cu" "F.Mask" "F.Paste")
			(net "MEMDQ_11")
		)
		(pad "C8" smd circle
			(at 2.400046 -4.400042)
			(size 0.3556 0.3556)
			(layers "F.Cu" "F.Mask" "F.Paste")
			(net "MEMDQ_13")
		)
		(pad "C9" smd circle
			(at 3.199892 -4.400042)
			(size 0.3556 0.3556)
			(layers "F.Cu" "F.Mask" "F.Paste")
			(net "GND")
		)
		(pad "D1" smd circle
			(at -3.199892 -3.599942)
			(size 0.3556 0.3556)
			(layers "F.Cu" "F.Mask" "F.Paste")
			(net "P1V2_STBY")
		)
		(pad "D2" smd circle
			(at -2.400046 -3.599942)
			(size 0.3556 0.3556)
			(layers "F.Cu" "F.Mask" "F.Paste")
			(net "GND")
		)
		(pad "D3" smd circle
			(at -1.599946 -3.599942)
			(size 0.3556 0.3556)
			(layers "F.Cu" "F.Mask" "F.Paste")
			(net "MEMDQ_14")
		)
		(pad "D7" smd circle
			(at 1.599946 -3.599942)
			(size 0.3556 0.3556)
			(layers "F.Cu" "F.Mask" "F.Paste")
			(net "MEMDQ_15")
		)
		(pad "D8" smd circle
			(at 2.400046 -3.599942)
			(size 0.3556 0.3556)
			(layers "F.Cu" "F.Mask" "F.Paste")
			(net "GND")
		)
		(pad "D9" smd circle
			(at 3.199892 -3.599942)
			(size 0.3556 0.3556)
			(layers "F.Cu" "F.Mask" "F.Paste")
			(net "P1V2_STBY")
		)
		(pad "E1" smd circle
			(at -3.199892 -2.800096)
			(size 0.3556 0.3556)
			(layers "F.Cu" "F.Mask" "F.Paste")
			(net "GND")
		)
		(pad "E2" smd circle
			(at -2.400046 -2.800096)
			(size 0.3556 0.3556)
			(layers "F.Cu" "F.Mask" "F.Paste")
			(net "MEMDM_1")
		)
		(pad "E3" smd circle
			(at -1.599946 -2.800096)
			(size 0.3556 0.3556)
			(layers "F.Cu" "F.Mask" "F.Paste")
			(net "GND")
		)
		(pad "E7" smd circle
			(at 1.599946 -2.800096)
			(size 0.3556 0.3556)
			(layers "F.Cu" "F.Mask" "F.Paste")
			(net "MEMDM_0")
		)
		(pad "E8" smd circle
			(at 2.400046 -2.800096)
			(size 0.3556 0.3556)
			(layers "F.Cu" "F.Mask" "F.Paste")
			(net "GND")
		)
		(pad "E9" smd circle
			(at 3.199892 -2.800096)
			(size 0.3556 0.3556)
			(layers "F.Cu" "F.Mask" "F.Paste")
			(net "GND")
		)
		(pad "F1" smd circle
			(at -3.199892 -1.999996)
			(size 0.3556 0.3556)
			(layers "F.Cu" "F.Mask" "F.Paste")
			(net "GND")
		)
		(pad "F2" smd circle
			(at -2.400046 -1.999996)
			(size 0.3556 0.3556)
			(layers "F.Cu" "F.Mask" "F.Paste")
			(net "P1V2_STBY")
		)
		(pad "F3" smd circle
			(at -1.599946 -1.999996)
			(size 0.3556 0.3556)
			(layers "F.Cu" "F.Mask" "F.Paste")
			(net "MEMDQS_N0")
		)
		(pad "F7" smd circle
			(at 1.599946 -1.999996)
			(size 0.3556 0.3556)
			(layers "F.Cu" "F.Mask" "F.Paste")
			(net "MEMDQ_1")
		)
		(pad "F8" smd circle
			(at 2.400046 -1.999996)
			(size 0.3556 0.3556)
			(layers "F.Cu" "F.Mask" "F.Paste")
			(net "P1V2_STBY")
		)
		(pad "F9" smd circle
			(at 3.199892 -1.999996)
			(size 0.3556 0.3556)
			(layers "F.Cu" "F.Mask" "F.Paste")
			(net "PD_ZQ")
		)
		(pad "G1" smd circle
			(at -3.199892 -1.199896)
			(size 0.3556 0.3556)
			(layers "F.Cu" "F.Mask" "F.Paste")
			(net "P1V2_STBY")
		)
		(pad "G2" smd circle
			(at -2.400046 -1.199896)
			(size 0.3556 0.3556)
			(layers "F.Cu" "F.Mask" "F.Paste")
			(net "MEMDQ_0")
		)
		(pad "G3" smd circle
			(at -1.599946 -1.199896)
			(size 0.3556 0.3556)
			(layers "F.Cu" "F.Mask" "F.Paste")
			(net "MEMDQS_P0")
		)
		(pad "G7" smd circle
			(at 1.599946 -1.199896)
			(size 0.3556 0.3556)
			(layers "F.Cu" "F.Mask" "F.Paste")
			(net "P1V2_STBY")
		)
		(pad "G8" smd circle
			(at 2.400046 -1.199896)
			(size 0.3556 0.3556)
			(layers "F.Cu" "F.Mask" "F.Paste")
			(net "GND")
		)
		(pad "G9" smd circle
			(at 3.199892 -1.199896)
			(size 0.3556 0.3556)
			(layers "F.Cu" "F.Mask" "F.Paste")
			(net "P1V2_STBY")
		)
		(pad "H1" smd circle
			(at -3.199892 -0.40005)
			(size 0.3556 0.3556)
			(layers "F.Cu" "F.Mask" "F.Paste")
			(net "GND")
		)
		(pad "H2" smd circle
			(at -2.400046 -0.40005)
			(size 0.3556 0.3556)
			(layers "F.Cu" "F.Mask" "F.Paste")
			(net "MEMDQ_4")
		)
		(pad "H3" smd circle
			(at -1.599946 -0.40005)
			(size 0.3556 0.3556)
			(layers "F.Cu" "F.Mask" "F.Paste")
			(net "MEMDQ_2")
		)
		(pad "H7" smd circle
			(at 1.599946 -0.40005)
			(size 0.3556 0.3556)
			(layers "F.Cu" "F.Mask" "F.Paste")
			(net "MEMDQ_3")
		)
		(pad "H8" smd circle
			(at 2.400046 -0.40005)
			(size 0.3556 0.3556)
			(layers "F.Cu" "F.Mask" "F.Paste")
			(net "MEMDQ_5")
		)
		(pad "H9" smd circle
			(at 3.199892 -0.40005)
			(size 0.3556 0.3556)
			(layers "F.Cu" "F.Mask" "F.Paste")
			(net "GND")
		)
		(pad "J1" smd circle
			(at -3.199892 0.40005)
			(size 0.3556 0.3556)
			(layers "F.Cu" "F.Mask" "F.Paste")
			(net "P1V2_STBY")
		)
		(pad "J2" smd circle
			(at -2.400046 0.40005)
			(size 0.3556 0.3556)
			(layers "F.Cu" "F.Mask" "F.Paste")
			(net "P1V2_STBY")
		)
		(pad "J3" smd circle
			(at -1.599946 0.40005)
			(size 0.3556 0.3556)
			(layers "F.Cu" "F.Mask" "F.Paste")
			(net "MEMDQ_6")
		)
		(pad "J7" smd circle
			(at 1.599946 0.40005)
			(size 0.3556 0.3556)
			(layers "F.Cu" "F.Mask" "F.Paste")
			(net "MEMDQ_7")
		)
		(pad "J8" smd circle
			(at 2.400046 0.40005)
			(size 0.3556 0.3556)
			(layers "F.Cu" "F.Mask" "F.Paste")
			(net "P1V2_STBY")
		)
		(pad "J9" smd circle
			(at 3.199892 0.40005)
			(size 0.3556 0.3556)
			(layers "F.Cu" "F.Mask" "F.Paste")
			(net "P1V2_STBY")
		)
		(pad "K1" smd circle
			(at -3.199892 1.199896)
			(size 0.3556 0.3556)
			(layers "F.Cu" "F.Mask" "F.Paste")
			(net "GND")
		)
		(pad "K2" smd circle
			(at -2.400046 1.199896)
			(size 0.3556 0.3556)
			(layers "F.Cu" "F.Mask" "F.Paste")
			(net "MEMCKE")
		)
		(pad "K3" smd circle
			(at -1.599946 1.199896)
			(size 0.3556 0.3556)
			(layers "F.Cu" "F.Mask" "F.Paste")
			(net "MEMODT")
		)
		(pad "K7" smd circle
			(at 1.599946 1.199896)
			(size 0.3556 0.3556)
			(layers "F.Cu" "F.Mask" "F.Paste")
			(net "MEMCK_P")
		)
		(pad "K8" smd circle
			(at 2.400046 1.199896)
			(size 0.3556 0.3556)
			(layers "F.Cu" "F.Mask" "F.Paste")
			(net "MEMCK_N")
		)
		(pad "K9" smd circle
			(at 3.199892 1.199896)
			(size 0.3556 0.3556)
			(layers "F.Cu" "F.Mask" "F.Paste")
			(net "GND")
		)
		(pad "L1" smd circle
			(at -3.199892 1.999996)
			(size 0.3556 0.3556)
			(layers "F.Cu" "F.Mask" "F.Paste")
			(net "P1V2_STBY")
		)
		(pad "L2" smd circle
			(at -2.400046 1.999996)
			(size 0.3556 0.3556)
			(layers "F.Cu" "F.Mask" "F.Paste")
			(net "MEMWEN")
		)
		(pad "L3" smd circle
			(at -1.599946 1.999996)
			(size 0.3556 0.3556)
			(layers "F.Cu" "F.Mask" "F.Paste")
			(net "DDR4_ACT")
		)
		(pad "L7" smd circle
			(at 1.599946 1.999996)
			(size 0.3556 0.3556)
			(layers "F.Cu" "F.Mask" "F.Paste")
			(net "MEMCSN")
		)
		(pad "L8" smd circle
			(at 2.400046 1.999996)
			(size 0.3556 0.3556)
			(layers "F.Cu" "F.Mask" "F.Paste")
			(net "MEMRASN")
		)
		(pad "L9" smd circle
			(at 3.199892 1.999996)
			(size 0.3556 0.3556)
			(layers "F.Cu" "F.Mask" "F.Paste")
			(net "P1V2_STBY")
		)
		(pad "M1" smd circle
			(at -3.199892 2.800096)
			(size 0.3556 0.3556)
			(layers "F.Cu" "F.Mask" "F.Paste")
			(net "DDR_VREF")
		)
		(pad "M2" smd circle
			(at -2.400046 2.800096)
			(size 0.3556 0.3556)
			(layers "F.Cu" "F.Mask" "F.Paste")
			(net "MEMBG_0")
		)
		(pad "M3" smd circle
			(at -1.599946 2.800096)
			(size 0.3556 0.3556)
			(layers "F.Cu" "F.Mask" "F.Paste")
			(net "MEMA_10")
		)
		(pad "M7" smd circle
			(at 1.599946 2.800096)
			(size 0.3556 0.3556)
			(layers "F.Cu" "F.Mask" "F.Paste")
			(net "MEMA_12")
		)
		(pad "M8" smd circle
			(at 2.400046 2.800096)
			(size 0.3556 0.3556)
			(layers "F.Cu" "F.Mask" "F.Paste")
			(net "MEMCASN")
		)
		(pad "M9" smd circle
			(at 3.199892 2.800096)
			(size 0.3556 0.3556)
			(layers "F.Cu" "F.Mask" "F.Paste")
			(net "GND")
		)
		(pad "N1" smd circle
			(at -3.199892 3.599942)
			(size 0.3556 0.3556)
			(layers "F.Cu" "F.Mask" "F.Paste")
			(net "GND")
		)
		(pad "N2" smd circle
			(at -2.400046 3.599942)
			(size 0.3556 0.3556)
			(layers "F.Cu" "F.Mask" "F.Paste")
			(net "MEMBA_0")
		)
		(pad "N3" smd circle
			(at -1.599946 3.599942)
			(size 0.3556 0.3556)
			(layers "F.Cu" "F.Mask" "F.Paste")
			(net "MEMA_4")
		)
		(pad "N7" smd circle
			(at 1.599946 3.599942)
			(size 0.3556 0.3556)
			(layers "F.Cu" "F.Mask" "F.Paste")
			(net "MEMA_3")
		)
		(pad "N8" smd circle
			(at 2.400046 3.599942)
			(size 0.3556 0.3556)
			(layers "F.Cu" "F.Mask" "F.Paste")
			(net "MEMBA_1")
		)
		(pad "N9" smd circle
			(at 3.199892 3.599942)
			(size 0.3556 0.3556)
			(layers "F.Cu" "F.Mask" "F.Paste")
			(net "GND")
		)
		(pad "P1" smd circle
			(at -3.199892 4.400042)
			(size 0.3556 0.3556)
			(layers "F.Cu" "F.Mask" "F.Paste")
			(net "DDR4_RST_N")
		)
		(pad "P2" smd circle
			(at -2.400046 4.400042)
			(size 0.3556 0.3556)
			(layers "F.Cu" "F.Mask" "F.Paste")
			(net "MEMA_6")
		)
		(pad "P3" smd circle
			(at -1.599946 4.400042)
			(size 0.3556 0.3556)
			(layers "F.Cu" "F.Mask" "F.Paste")
			(net "MEMA_0")
		)
		(pad "P7" smd circle
			(at 1.599946 4.400042)
			(size 0.3556 0.3556)
			(layers "F.Cu" "F.Mask" "F.Paste")
			(net "MEMA_1")
		)
		(pad "P8" smd circle
			(at 2.400046 4.400042)
			(size 0.3556 0.3556)
			(layers "F.Cu" "F.Mask" "F.Paste")
			(net "MEMA_5")
		)
		(pad "P9" smd circle
			(at 3.199892 4.400042)
			(size 0.3556 0.3556)
			(layers "F.Cu" "F.Mask" "F.Paste")
			(net "DDR4_ALERT")
		)
		(pad "R1" smd circle
			(at -3.199892 5.199888)
			(size 0.3556 0.3556)
			(layers "F.Cu" "F.Mask" "F.Paste")
			(net "P1V2_STBY")
		)
		(pad "R2" smd circle
			(at -2.400046 5.199888)
			(size 0.3556 0.3556)
			(layers "F.Cu" "F.Mask" "F.Paste")
			(net "MEMA_8")
		)
		(pad "R3" smd circle
			(at -1.599946 5.199888)
			(size 0.3556 0.3556)
			(layers "F.Cu" "F.Mask" "F.Paste")
			(net "MEMA_2")
		)
		(pad "R7" smd circle
			(at 1.599946 5.199888)
			(size 0.3556 0.3556)
			(layers "F.Cu" "F.Mask" "F.Paste")
			(net "MEMA_9")
		)
		(pad "R8" smd circle
			(at 2.400046 5.199888)
			(size 0.3556 0.3556)
			(layers "F.Cu" "F.Mask" "F.Paste")
			(net "MEMA_7")
		)
		(pad "R9" smd circle
			(at 3.199892 5.199888)
			(size 0.3556 0.3556)
			(layers "F.Cu" "F.Mask" "F.Paste")
			(net "P2V5_STBY")
		)
		(pad "T1" smd circle
			(at -3.199892 5.999988)
			(size 0.3556 0.3556)
			(layers "F.Cu" "F.Mask" "F.Paste")
			(net "GND")
		)
		(pad "T2" smd circle
			(at -2.400046 5.999988)
			(size 0.3556 0.3556)
			(layers "F.Cu" "F.Mask" "F.Paste")
			(net "MEMA_11")
		)
		(pad "T3" smd circle
			(at -1.599946 5.999988)
			(size 0.3556 0.3556)
			(layers "F.Cu" "F.Mask" "F.Paste")
			(net "MEM_PAR")
		)
		(pad "T7" smd circle
			(at 1.599946 5.999988)
			(size 0.3556 0.3556)
			(layers "F.Cu" "F.Mask" "F.Paste")
			(net "Net_542")
		)
		(pad "T8" smd circle
			(at 2.400046 5.999988)
			(size 0.3556 0.3556)
			(layers "F.Cu" "F.Mask" "F.Paste")
			(net "MEMA_13")
		)
		(pad "T9" smd circle
			(at 3.199892 5.999988)
			(size 0.3556 0.3556)
			(layers "F.Cu" "F.Mask" "F.Paste")
			(net "P1V2_STBY")
		)
	)
)
